#ISCELL
  mstr_misc dns *
  *
#ISCELL
  mstr_symbols design_note *
  *
#ISCELL
  mstr_symbols intel_corp_bpage *
  *
#ISCELL
  mstr_symbols p3v3_stby *
  page213_i1
#ISCELL
  mstr_symbols gnd *
  page213_i10
#CELL
  dev_discrete cap_a *
  page213_i11
#ISCELL
  mstr_symbols gnd *
  page213_i12
#CELL
  mstr_discrete res *
  page213_i13
#CELL
  mstr_discrete res *
  page213_i14
#CELL
  mstr_discrete res *
  page213_i15
#CELL
  mstr_discrete res *
  page213_i16
#CELL
  dev_discrete cap_a *
  page213_i17
#ISCELL
  mstr_symbols gnd *
  page213_i18
#ISCELL
  mstr_standard offpage *
  page213_i2
#ISCELL
  mstr_symbols gnd *
  page213_i21
#ISCELL
  mstr_symbols p3v3_stby *
  page213_i24
#CELL
  mstr_discrete res *
  page213_i25
#ISCELL
  mstr_symbols pvccio_cpu1 *
  page213_i26
#CELL
  mstr_discrete res *
  page213_i27
#ISCELL
  mstr_symbols pvccio_cpu1 *
  page213_i28
#ISCELL
  mstr_standard offpage *
  page213_i3
#CELL
  mstr_discrete res *
  page213_i30
#CELL
  mstr_discrete res *
  page213_i31
#CELL
  mstr_discrete res *
  page213_i32
#CELL
  mstr_discrete cap *
  page213_i33
#ISCELL
  mstr_standard offpage *
  page213_i34
#CELL
  dev_discrete cap_a *
  page213_i35
#ISCELL
  mstr_symbols gnd *
  page213_i36
#CELL
  mstr_discrete res *
  page213_i37
#CELL
  mstr_discrete res *
  page213_i38
#CELL
  mstr_discrete res *
  page213_i39
#CELL
  mstr_discrete res *
  page213_i42
#ISCELL
  mstr_symbols gnd *
  page213_i44
#ISCELL
  mstr_symbols gnd *
  page213_i45
#CELL
  mstr_discrete res *
  page213_i46
#ISCELL
  mstr_symbols gnd *
  page213_i47
#ISCELL
  mstr_symbols gnd *
  page213_i49
#ISCELL
  mstr_standard offpage *
  page213_i5
#ISCELL
  mstr_standard offpage *
  page213_i50
#ISCELL
  mstr_standard offpage *
  page213_i51
#ISCELL
  mstr_standard offpage *
  page213_i52
#ISCELL
  mstr_standard offpage *
  page213_i53
#ISCELL
  mstr_standard offpage *
  page213_i54
#ISCELL
  mstr_standard offpage *
  page213_i55
#ISCELL
  mstr_standard offpage *
  page213_i57
#ISCELL
  mstr_standard offpage *
  page213_i58
#ISCELL
  mstr_standard offpage *
  page213_i61
#ISCELL
  mstr_standard offpage *
  page213_i62
#CELL
  mstr_discrete res *
  page213_i63
#CELL
  mstr_discrete res *
  page213_i65
#CELL
  mstr_discrete cap *
  page213_i73
#ISCELL
  mstr_symbols gnd *
  page213_i74
#ISCELL
  mstr_standard offpage *
  page213_i8
#CELL
  mstr_discrete cap *
  page213_i83
#CELL
  mstr_discrete res *
  page213_i84
#ISCELL
  mstr_standard offpage *
  page213_i86
#ISCELL
  mstr_standard offpage *
  page213_i87
#CELL
  dev_discrete cap_a *
  page213_i9
#CELL
  mstr_discrete res *
  page213_i90
#CELL
  mstr_discrete res *
  page213_i91
#ISCELL
  mstr_symbols universal_power *
  page213_i92
#CELL
  mstr_discrete res *
  page213_i94
#ISCELL
  mstr_standard offpage *
  page213_i95
#CELL
  mstr_controller pxe1110b *
  page213_i96
